(kicad_pcb
	(version 20260206)
	(generator "pcbnew")
	(generator_version "10.0")
	(general
		(thickness 1.6)
		(legacy_teardrops no)
	)
	(paper "A4")
	(title_block
		(title "timecard-production-celestica-r4006 — R4006-B0001-02_R01.brd")
		(comment 1 "Time Appliance Project (Time Card) / footprints 333-339 of 1113")
	)
	(layers
		(0 "F.Cu" signal "TOP")
		(4 "In1.Cu" signal "L02_GND1")
		(6 "In2.Cu" signal "L03_SIG1")
		(8 "In3.Cu" signal "L04_GND2")
		(10 "In4.Cu" signal "L05_VCC1")
		(12 "In5.Cu" signal "L06_VCC2")
		(14 "In6.Cu" signal "L07_GND3")
		(16 "In7.Cu" signal "L08_SIG2")
		(18 "In8.Cu" signal "L09_GND4")
		(2 "B.Cu" signal "BOTTOM")
		(9 "F.Adhes" user "F.Adhesive")
		(11 "B.Adhes" user "B.Adhesive")
		(13 "F.Paste" user "Package Geometry/Pastemask Top")
		(15 "B.Paste" user "Package Geometry/Pastemask Bottom")
		(5 "F.SilkS" user "Ref Des/Silkscreen Top")
		(7 "B.SilkS" user "Ref Des/Silkscreen Bottom")
		(1 "F.Mask" user "Board Geometry/Soldermask Top")
		(3 "B.Mask" user "Board Geometry/Soldermask Bottom")
		(17 "Dwgs.User" user "User.Drawings")
		(19 "Cmts.User" user "User.Comments")
		(21 "Eco1.User" user "User.Eco1")
		(23 "Eco2.User" user "User.Eco2")
		(25 "Edge.Cuts" user "Board Geometry/Outline")
		(27 "Margin" user)
		(31 "F.CrtYd" user "Package Geometry/Place Bound Top")
		(29 "B.CrtYd" user "Package Geometry/Place Bound Bottom")
		(35 "F.Fab" user "Ref Des/Assembly Top")
		(33 "B.Fab" user "Ref Des/Assembly Bottom")
	)
	(footprint ""
		(layer "F.Cu")
		(at 15.875 -28.067 -90)
		(property "Reference" "C83"
			(at 0.127 -1.81737 90)
			(unlocked yes)
			(layer "F.SilkS")
			(effects
				(font
					(size 0.7874 0.5842)
					(thickness 0.1524)
				)
			)
		)
		(property "Value" "VAL*"
			(at 0.0762 2.067306 270)
			(unlocked yes)
			(layer "F.Fab")
			(hide yes)
			(effects
				(font
					(size 0.7874 0.5842)
					(thickness 0.1524)
				)
			)
		)
		(property "Device Type" "CAPACITOR-G105-0B104-CK,0.1UF,A"
			(at 0.0508 1.127506 270)
			(unlocked yes)
			(layer "F.Fab")
			(hide yes)
			(effects
				(font
					(size 0.7874 0.5842)
					(thickness 0.1524)
				)
			)
		)
		(property "User Part Number" "PARTNUM*"
			(at 0.1016 4.023106 270)
			(unlocked yes)
			(layer "Cmts.User")
			(hide yes)
			(effects
				(font
					(size 0.7874 0.5842)
					(thickness 0.1524)
				)
			)
		)
		(property "Tolerance" "TOL*"
			(at 0.0762 3.032506 270)
			(unlocked yes)
			(layer "Cmts.User")
			(hide yes)
			(effects
				(font
					(size 0.7874 0.5842)
					(thickness 0.1524)
				)
			)
		)
		(duplicate_pad_numbers_are_jumpers no)
		(fp_line
			(start -1.143 0.5588)
			(end 1.143 0.5588)
			(stroke
				(width 0.1)
				(type default)
			)
			(layer "F.SilkS")
		)
		(fp_line
			(start 1.143 0.5588)
			(end 1.143 -0.5588)
			(stroke
				(width 0.1)
				(type default)
			)
			(layer "F.SilkS")
		)
		(fp_line
			(start -1.143 -0.5588)
			(end -1.143 0.5588)
			(stroke
				(width 0.1)
				(type default)
			)
			(layer "F.SilkS")
		)
		(fp_line
			(start 1.143 -0.5588)
			(end -1.143 -0.5588)
			(stroke
				(width 0.1)
				(type default)
			)
			(layer "F.SilkS")
		)
		(fp_rect
			(start -1.143 -0.5588)
			(end 1.143 0.5588)
			(stroke
				(width 0)
				(type default)
			)
			(fill no)
			(layer "F.CrtYd")
		)
		(fp_line
			(start -0.508 0.3048)
			(end 0.508 0.3048)
			(stroke
				(width 0.1)
				(type default)
			)
			(layer "F.Fab")
		)
		(fp_line
			(start 0.508 0.3048)
			(end 0.508 -0.3048)
			(stroke
				(width 0.1)
				(type default)
			)
			(layer "F.Fab")
		)
		(fp_line
			(start -0.508 -0.3048)
			(end -0.508 0.3048)
			(stroke
				(width 0.1)
				(type default)
			)
			(layer "F.Fab")
		)
		(fp_line
			(start 0.508 -0.3048)
			(end -0.508 -0.3048)
			(stroke
				(width 0.1)
				(type default)
			)
			(layer "F.Fab")
		)
		(pad "1" smd rect
			(at -0.5334 0 270)
			(size 0.7112 0.6096)
			(layers "F.Cu" "F.Mask" "F.Paste")
			(net "XP3R3V_FPGA")
		)
		(pad "2" smd rect
			(at 0.5334 0 270)
			(size 0.7112 0.6096)
			(layers "F.Cu" "F.Mask" "F.Paste")
			(net "SG")
		)
		(zone
			(layer "F.Cu")
			(hatch none 0.5)
			(connect_pads
				(clearance 0)
			)
			(min_thickness 0.25)
			(keepout
				(tracks allowed)
				(vias not_allowed)
				(pads allowed)
				(copperpour not_allowed)
				(footprints allowed)
			)
			(placement
				(enabled no)
				(sheetname "")
			)
			(fill
				(thermal_gap 0.5)
				(thermal_bridge_width 0.5)
				(island_removal_mode 0)
			)
			(polygon
				(pts
					(xy 16.1798 -28.1432) (xy 15.5702 -28.1432) (xy 15.5702 -27.9908) (xy 16.1798 -27.9908)
				)
			)
		)
	)
	(footprint ""
		(layer "F.Cu")
		(at 150.049992 -104.350058 -90)
		(property "Reference" "DS19"
			(at 0.845058 -1.424178 90)
			(unlocked yes)
			(layer "F.SilkS")
			(effects
				(font
					(size 0.7874 0.5842)
					(thickness 0.1524)
				)
			)
		)
		(property "Value" ""
			(at 0 0 270)
			(layer "F.Fab")
			(effects
				(font
					(size 1.27 1.27)
				)
			)
		)
		(property "Device Type" "OPTICAL-G170-10143-01"
			(at 0.1778 1.483081 270)
			(unlocked yes)
			(layer "F.Fab")
			(hide yes)
			(effects
				(font
					(size 0.786892 0.583946)
					(thickness 0.000001)
				)
			)
		)
		(property "User Part Number" "PARTNUM*"
			(at 0.1778 2.422881 270)
			(unlocked yes)
			(layer "Cmts.User")
			(hide yes)
			(effects
				(font
					(size 0.786892 0.583946)
					(thickness 0.000001)
				)
			)
		)
		(duplicate_pad_numbers_are_jumpers no)
		(fp_line
			(start -1.397508 0.704088)
			(end -1.397508 -0.704088)
			(stroke
				(width 0.1)
				(type default)
			)
			(layer "F.SilkS")
		)
		(fp_line
			(start 1.397508 0.704088)
			(end -1.397508 0.704088)
			(stroke
				(width 0.1)
				(type default)
			)
			(layer "F.SilkS")
		)
		(fp_line
			(start -2.3368 0.0762)
			(end -3.6068 0.0762)
			(stroke
				(width 0.1)
				(type default)
			)
			(layer "F.SilkS")
		)
		(fp_line
			(start -2.9718 -0.5588)
			(end -2.9718 0.7112)
			(stroke
				(width 0.1)
				(type default)
			)
			(layer "F.SilkS")
		)
		(fp_line
			(start -1.397508 -0.704088)
			(end 1.397508 -0.704088)
			(stroke
				(width 0.1)
				(type default)
			)
			(layer "F.SilkS")
		)
		(fp_line
			(start 1.397508 -0.704088)
			(end 1.397508 0.704088)
			(stroke
				(width 0.1)
				(type default)
			)
			(layer "F.SilkS")
		)
		(fp_poly
			(pts
				(xy 1.397508 0.704088) (xy 1.397508 -0.704088) (xy 1.905508 -0.704088) (xy 1.905508 0.704088)
			)
			(stroke
				(width 0)
				(type default)
			)
			(fill yes)
			(layer "F.SilkS")
		)
		(fp_poly
			(pts
				(xy -1.651508 0.958088) (xy 1.905508 0.958088) (xy 1.905508 -0.958088) (xy -1.651508 -0.958088)
			)
			(stroke
				(width 0)
				(type default)
			)
			(fill no)
			(layer "F.CrtYd")
		)
		(fp_line
			(start -0.850138 0.450088)
			(end 0.850138 0.450088)
			(stroke
				(width 0.1)
				(type default)
			)
			(layer "F.Fab")
		)
		(fp_line
			(start 0.850138 0.450088)
			(end 0.850138 -0.450088)
			(stroke
				(width 0.1)
				(type default)
			)
			(layer "F.Fab")
		)
		(fp_line
			(start -2.4638 0.0762)
			(end -3.7338 0.0762)
			(stroke
				(width 0.1)
				(type default)
			)
			(layer "F.Fab")
		)
		(fp_line
			(start -0.850138 -0.450088)
			(end -0.850138 0.450088)
			(stroke
				(width 0.1)
				(type default)
			)
			(layer "F.Fab")
		)
		(fp_line
			(start 0.850138 -0.450088)
			(end -0.850138 -0.450088)
			(stroke
				(width 0.1)
				(type default)
			)
			(layer "F.Fab")
		)
		(fp_line
			(start -3.0988 -0.5588)
			(end -3.0988 0.7112)
			(stroke
				(width 0.1)
				(type default)
			)
			(layer "F.Fab")
		)
		(fp_poly
			(pts
				(xy 0.850138 -0.450088) (xy 0.850138 0.450088) (xy 0.342138 0.450088) (xy 0.342138 -0.450088)
			)
			(stroke
				(width 0)
				(type default)
			)
			(fill yes)
			(layer "F.Fab")
		)
		(fp_text user "A"
			(at -2.044192 0.697992 0)
			(unlocked yes)
			(layer "F.SilkS")
			(effects
				(font
					(size 0.635 0.4064)
					(thickness 0.1524)
				)
			)
		)
		(fp_text user "C"
			(at 2.527808 0.189992 0)
			(unlocked yes)
			(layer "F.SilkS")
			(effects
				(font
					(size 0.635 0.4064)
					(thickness 0.1524)
				)
			)
		)
		(fp_text user "A"
			(at -1.9558 0.142748 90)
			(unlocked yes)
			(layer "F.Fab")
			(effects
				(font
					(size 0.7874 0.5842)
					(thickness 0.1524)
				)
			)
		)
		(fp_text user "C"
			(at 1.900428 -0.826008 0)
			(unlocked yes)
			(layer "F.Fab")
			(effects
				(font
					(size 0.7874 0.5842)
					(thickness 0.1524)
				)
			)
		)
		(pad "A" smd rect
			(at -0.749808 0 270)
			(size 0.7874 0.7874)
			(layers "F.Cu" "F.Mask" "F.Paste")
			(net "UNNAMED_14_OPTICAL_I191_A")
		)
		(pad "C" smd rect
			(at 0.749808 0 270)
			(size 0.7874 0.7874)
			(layers "F.Cu" "F.Mask" "F.Paste")
			(net "SG")
		)
	)
	(footprint ""
		(layer "F.Cu")
		(at 56.007 -127.635)
		(property "Reference" "SP50"
			(at 0 0 0)
			(layer "F.SilkS")
			(hide yes)
			(effects
				(font
					(size 1.27 1.27)
				)
			)
		)
		(property "Value" ""
			(at 0 0 0)
			(layer "F.Fab")
			(effects
				(font
					(size 1.27 1.27)
				)
			)
		)
		(duplicate_pad_numbers_are_jumpers no)
	)
	(footprint ""
		(layer "F.Cu")
		(at 96.5454 -64.2874 -90)
		(property "Reference" "R285"
			(at 2.6924 -0.77597 90)
			(unlocked yes)
			(layer "F.SilkS")
			(effects
				(font
					(size 0.7874 0.5842)
					(thickness 0.1524)
				)
			)
		)
		(property "Value" "VAL*"
			(at 0.02032 2.13233 270)
			(unlocked yes)
			(layer "F.Fab")
			(hide yes)
			(effects
				(font
					(size 0.7874 0.5842)
					(thickness 0.1524)
				)
			)
		)
		(property "Tolerance" "TOL*"
			(at 0.044704 3.05435 270)
			(unlocked yes)
			(layer "Cmts.User")
			(hide yes)
			(effects
				(font
					(size 0.7874 0.5842)
					(thickness 0.1524)
				)
			)
		)
		(property "User Part Number" "PARTNUM*"
			(at 0.02032 4.024884 270)
			(unlocked yes)
			(layer "Cmts.User")
			(hide yes)
			(effects
				(font
					(size 0.7874 0.5842)
					(thickness 0.1524)
				)
			)
		)
		(property "Device Type" "RESISTOR-G155-11002-01,10KOHM,A"
			(at 0.008382 1.210564 270)
			(unlocked yes)
			(layer "F.Fab")
			(hide yes)
			(effects
				(font
					(size 0.7874 0.5842)
					(thickness 0.1524)
				)
			)
		)
		(duplicate_pad_numbers_are_jumpers no)
		(fp_line
			(start -1.143 0.5588)
			(end 1.143 0.5588)
			(stroke
				(width 0.1)
				(type default)
			)
			(layer "F.SilkS")
		)
		(fp_line
			(start 1.143 0.5588)
			(end 1.143 -0.5588)
			(stroke
				(width 0.1)
				(type default)
			)
			(layer "F.SilkS")
		)
		(fp_line
			(start -1.143 -0.5588)
			(end -1.143 0.5588)
			(stroke
				(width 0.1)
				(type default)
			)
			(layer "F.SilkS")
		)
		(fp_line
			(start 1.143 -0.5588)
			(end -1.143 -0.5588)
			(stroke
				(width 0.1)
				(type default)
			)
			(layer "F.SilkS")
		)
		(fp_poly
			(pts
				(xy -1.143 0.5588) (xy 1.143 0.5588) (xy 1.143 -0.5588) (xy -1.143 -0.5588)
			)
			(stroke
				(width 0)
				(type default)
			)
			(fill no)
			(layer "F.CrtYd")
		)
		(fp_line
			(start -0.508 0.3048)
			(end 0.508 0.3048)
			(stroke
				(width 0.1)
				(type default)
			)
			(layer "F.Fab")
		)
		(fp_line
			(start 0.508 0.3048)
			(end 0.508 -0.3048)
			(stroke
				(width 0.1)
				(type default)
			)
			(layer "F.Fab")
		)
		(fp_line
			(start -0.508 -0.3048)
			(end -0.508 0.3048)
			(stroke
				(width 0.1)
				(type default)
			)
			(layer "F.Fab")
		)
		(fp_line
			(start 0.508 -0.3048)
			(end -0.508 -0.3048)
			(stroke
				(width 0.1)
				(type default)
			)
			(layer "F.Fab")
		)
		(pad "1" smd rect
			(at -0.5334 0 270)
			(size 0.7112 0.6096)
			(layers "F.Cu" "F.Mask" "F.Paste")
			(net "XP3R3V_FPGA")
		)
		(pad "2" smd rect
			(at 0.5334 0 270)
			(size 0.7112 0.6096)
			(layers "F.Cu" "F.Mask" "F.Paste")
			(net "FPGA_IO_3")
		)
		(zone
			(layer "F.Cu")
			(hatch none 0.5)
			(connect_pads
				(clearance 0)
			)
			(min_thickness 0.25)
			(keepout
				(tracks not_allowed)
				(vias allowed)
				(pads allowed)
				(copperpour not_allowed)
				(footprints allowed)
			)
			(placement
				(enabled no)
				(sheetname "")
			)
			(fill
				(thermal_gap 0.5)
				(thermal_bridge_width 0.5)
				(island_removal_mode 0)
			)
			(polygon
				(pts
					(xy 96.2406 -64.3636) (xy 96.2406 -64.2112) (xy 96.8502 -64.2112) (xy 96.8502 -64.3636)
				)
			)
		)
		(zone
			(layer "F.Cu")
			(hatch none 0.5)
			(connect_pads
				(clearance 0)
			)
			(min_thickness 0.25)
			(keepout
				(tracks allowed)
				(vias not_allowed)
				(pads allowed)
				(copperpour not_allowed)
				(footprints allowed)
			)
			(placement
				(enabled no)
				(sheetname "")
			)
			(fill
				(thermal_gap 0.5)
				(thermal_bridge_width 0.5)
				(island_removal_mode 0)
			)
			(polygon
				(pts
					(xy 96.2406 -64.3636) (xy 96.2406 -64.2112) (xy 96.8502 -64.2112) (xy 96.8502 -64.3636)
				)
			)
		)
	)
	(footprint ""
		(layer "F.Cu")
		(at 97.4598 -69.215)
		(property "Reference" "R189"
			(at -28.1178 -18.88363 0)
			(unlocked yes)
			(layer "F.SilkS")
			(effects
				(font
					(size 0.7874 0.5842)
					(thickness 0.1524)
				)
			)
		)
		(property "Value" "VAL*"
			(at 0.02032 2.13233 0)
			(unlocked yes)
			(layer "F.Fab")
			(hide yes)
			(effects
				(font
					(size 0.7874 0.5842)
					(thickness 0.1524)
				)
			)
		)
		(property "Tolerance" "TOL*"
			(at 0.044704 3.05435 0)
			(unlocked yes)
			(layer "Cmts.User")
			(hide yes)
			(effects
				(font
					(size 0.7874 0.5842)
					(thickness 0.1524)
				)
			)
		)
		(property "User Part Number" "PARTNUM*"
			(at 0.02032 4.024884 0)
			(unlocked yes)
			(layer "Cmts.User")
			(hide yes)
			(effects
				(font
					(size 0.7874 0.5842)
					(thickness 0.1524)
				)
			)
		)
		(property "Device Type" "RESISTOR-G155-03241-01,3.24KOHA"
			(at 0.008382 1.210564 0)
			(unlocked yes)
			(layer "F.Fab")
			(hide yes)
			(effects
				(font
					(size 0.7874 0.5842)
					(thickness 0.1524)
				)
			)
		)
		(duplicate_pad_numbers_are_jumpers no)
		(fp_line
			(start -1.143 -0.5588)
			(end -1.143 0.5588)
			(stroke
				(width 0.1)
				(type default)
			)
			(layer "F.SilkS")
		)
		(fp_line
			(start -1.143 0.5588)
			(end 1.143 0.5588)
			(stroke
				(width 0.1)
				(type default)
			)
			(layer "F.SilkS")
		)
		(fp_line
			(start 1.143 -0.5588)
			(end -1.143 -0.5588)
			(stroke
				(width 0.1)
				(type default)
			)
			(layer "F.SilkS")
		)
		(fp_line
			(start 1.143 0.5588)
			(end 1.143 -0.5588)
			(stroke
				(width 0.1)
				(type default)
			)
			(layer "F.SilkS")
		)
		(fp_rect
			(start -1.143 -0.5588)
			(end 1.143 0.5588)
			(stroke
				(width 0)
				(type default)
			)
			(fill no)
			(layer "F.CrtYd")
		)
		(fp_line
			(start -0.508 -0.3048)
			(end -0.508 0.3048)
			(stroke
				(width 0.1)
				(type default)
			)
			(layer "F.Fab")
		)
		(fp_line
			(start -0.508 0.3048)
			(end 0.508 0.3048)
			(stroke
				(width 0.1)
				(type default)
			)
			(layer "F.Fab")
		)
		(fp_line
			(start 0.508 -0.3048)
			(end -0.508 -0.3048)
			(stroke
				(width 0.1)
				(type default)
			)
			(layer "F.Fab")
		)
		(fp_line
			(start 0.508 0.3048)
			(end 0.508 -0.3048)
			(stroke
				(width 0.1)
				(type default)
			)
			(layer "F.Fab")
		)
		(pad "1" smd rect
			(at -0.5334 0)
			(size 0.7112 0.6096)
			(layers "F.Cu" "F.Mask" "F.Paste")
			(net "SG")
		)
		(pad "2" smd rect
			(at 0.5334 0)
			(size 0.7112 0.6096)
			(layers "F.Cu" "F.Mask" "F.Paste")
			(net "XP1R2V_FB")
		)
		(zone
			(layer "F.Cu")
			(hatch none 0.5)
			(connect_pads
				(clearance 0)
			)
			(min_thickness 0.25)
			(keepout
				(tracks allowed)
				(vias not_allowed)
				(pads allowed)
				(copperpour not_allowed)
				(footprints allowed)
			)
			(placement
				(enabled no)
				(sheetname "")
			)
			(fill
				(thermal_gap 0.5)
				(thermal_bridge_width 0.5)
				(island_removal_mode 0)
			)
			(polygon
				(pts
					(xy 97.3836 -69.5198) (xy 97.3836 -68.9102) (xy 97.536 -68.9102) (xy 97.536 -69.5198)
				)
			)
		)
	)
	(footprint ""
		(layer "F.Cu")
		(at 59.69 -127.127)
		(property "Reference" "SP45"
			(at 0 0 0)
			(layer "F.SilkS")
			(hide yes)
			(effects
				(font
					(size 1.27 1.27)
				)
			)
		)
		(property "Value" ""
			(at 0 0 0)
			(layer "F.Fab")
			(effects
				(font
					(size 1.27 1.27)
				)
			)
		)
		(duplicate_pad_numbers_are_jumpers no)
	)
	(footprint ""
		(layer "F.Cu")
		(at 141.05001 -107.849924 -90)
		(property "Reference" "DS2"
			(at 0.026924 1.36906 90)
			(unlocked yes)
			(layer "F.SilkS")
			(effects
				(font
					(size 0.635 0.4064)
					(thickness 0.1524)
				)
			)
		)
		(property "Value" ""
			(at 0 0 270)
			(layer "F.Fab")
			(effects
				(font
					(size 1.27 1.27)
				)
			)
		)
		(property "User Part Number" "PARTNUM*"
			(at 0.1778 2.422881 270)
			(unlocked yes)
			(layer "Cmts.User")
			(hide yes)
			(effects
				(font
					(size 0.786892 0.583946)
					(thickness 0.000001)
				)
			)
		)
		(property "Device Type" "OPTICAL-G170-10143-01"
			(at 0.1778 1.483081 270)
			(unlocked yes)
			(layer "F.Fab")
			(hide yes)
			(effects
				(font
					(size 0.786892 0.583946)
					(thickness 0.000001)
				)
			)
		)
		(duplicate_pad_numbers_are_jumpers no)
		(fp_line
			(start -1.3208 1.0922)
			(end -2.5908 1.0922)
			(stroke
				(width 0.1)
				(type default)
			)
			(layer "F.SilkS")
		)
		(fp_line
			(start -1.397508 0.704088)
			(end -1.397508 -0.704088)
			(stroke
				(width 0.1)
				(type default)
			)
			(layer "F.SilkS")
		)
		(fp_line
			(start 1.397508 0.704088)
			(end -1.397508 0.704088)
			(stroke
				(width 0.1)
				(type default)
			)
			(layer "F.SilkS")
		)
		(fp_line
			(start -1.9558 0.4572)
			(end -1.9558 1.7272)
			(stroke
				(width 0.1)
				(type default)
			)
			(layer "F.SilkS")
		)
		(fp_line
			(start -1.397508 -0.704088)
			(end 1.397508 -0.704088)
			(stroke
				(width 0.1)
				(type default)
			)
			(layer "F.SilkS")
		)
		(fp_line
			(start 1.397508 -0.704088)
			(end 1.397508 0.704088)
			(stroke
				(width 0.1)
				(type default)
			)
			(layer "F.SilkS")
		)
		(fp_rect
			(start 1.905508 0.704088)
			(end 1.397508 -0.704088)
			(stroke
				(width 0)
				(type default)
			)
			(fill yes)
			(layer "F.SilkS")
		)
		(fp_rect
			(start 1.905508 0.958088)
			(end -1.651508 -0.958088)
			(stroke
				(width 0)
				(type default)
			)
			(fill no)
			(layer "F.CrtYd")
		)
		(fp_line
			(start -1.5748 1.0922)
			(end -2.8448 1.0922)
			(stroke
				(width 0.1)
				(type default)
			)
			(layer "F.Fab")
		)
		(fp_line
			(start -2.2098 0.4572)
			(end -2.2098 1.7272)
			(stroke
				(width 0.1)
				(type default)
			)
			(layer "F.Fab")
		)
		(fp_line
			(start -0.850138 0.450088)
			(end 0.850138 0.450088)
			(stroke
				(width 0.1)
				(type default)
			)
			(layer "F.Fab")
		)
		(fp_line
			(start 0.850138 0.450088)
			(end 0.850138 -0.450088)
			(stroke
				(width 0.1)
				(type default)
			)
			(layer "F.Fab")
		)
		(fp_line
			(start -0.850138 -0.450088)
			(end -0.850138 0.450088)
			(stroke
				(width 0.1)
				(type default)
			)
			(layer "F.Fab")
		)
		(fp_line
			(start 0.850138 -0.450088)
			(end -0.850138 -0.450088)
			(stroke
				(width 0.1)
				(type default)
			)
			(layer "F.Fab")
		)
		(fp_rect
			(start 0.850138 0.450088)
			(end 0.342138 -0.450088)
			(stroke
				(width 0)
				(type default)
			)
			(fill yes)
			(layer "F.Fab")
		)
		(fp_text user "C"
			(at 1.455674 1.60401 0)
			(unlocked yes)
			(layer "F.SilkS")
			(effects
				(font
					(size 0.635 0.4064)
					(thickness 0.1524)
				)
			)
		)
		(fp_text user "A"
			(at -1.846326 -0.68199 0)
			(unlocked yes)
			(layer "F.SilkS")
			(effects
				(font
					(size 0.635 0.4064)
					(thickness 0.1524)
				)
			)
		)
		(fp_text user "A"
			(at -1.700276 0.096012 0)
			(unlocked yes)
			(layer "F.Fab")
			(effects
				(font
					(size 0.7874 0.5842)
					(thickness 0.1524)
				)
			)
		)
		(fp_text user "C"
			(at 1.844294 -0.80899 0)
			(unlocked yes)
			(layer "F.Fab")
			(effects
				(font
					(size 0.7874 0.5842)
					(thickness 0.1524)
				)
			)
		)
		(pad "A" smd rect
			(at -0.749808 0 270)
			(size 0.7874 0.7874)
			(layers "F.Cu" "F.Mask" "F.Paste")
			(net "UNNAMED_14_OPTICAL_I11_A")
		)
		(pad "C" smd rect
			(at 0.749808 0 270)
			(size 0.7874 0.7874)
			(layers "F.Cu" "F.Mask" "F.Paste")
			(net "LED_DATOUT2")
		)
	)
)
